# T6G (Grand Teton) — schematic netlist excerpt (pin names and nets, part order shuffled) for the footprints in the layout excerpt that follows; sources: Cadence DE-HDL packaged netlist, KiCad conversion of 04192023_DAF0TMB3IC0_F0TG_MB_C_brd_V02_OCP.brd

R8102  Q_RES  0 5% CHIP  pkg 0402LF  page 240 : A = FM_AC_PWR_BTN_R_N ; B = FM_AC_PWR_BTN_PDB_N
C769  Q_CAP_DIFFBUS  DIFF BUS_0.22UF 6.3V 20% X6S  pkg C0201  page 66 : \1\ = P5E_CPU1_P2_TX_C_DP<2> ; \2\ = P5E_CPU1_P2_TX_DP<2>
C2159  Q_CAP  22UF 4V 20% X6S  pkg C0402  page 68 : A = PVDDCR_SOC_P0 ; B = GND

(kicad_pcb
	(version 20260206)
	(generator "pcbnew")
	(generator_version "10.0")
	(general
		(thickness 1.6)
		(legacy_teardrops no)
	)
	(paper "A4")
	(title_block
		(title "04192023_DAF0TMB3IC0_F0TG_MB_C_brd_V02_OCP.brd")
		(comment 1 "Grand Teton / footprints 3501-3503 of 8354")
	)
	(layers
		(0 "F.Cu" signal "TOP")
		(4 "In1.Cu" signal "GND")
		(6 "In2.Cu" signal "IN1")
		(8 "In3.Cu" signal "GND1")
		(10 "In4.Cu" signal "IN2")
		(12 "In5.Cu" signal "GND2")
		(14 "In6.Cu" signal "IN3")
		(16 "In7.Cu" signal "GND3")
		(18 "In8.Cu" signal "VCC")
		(20 "In9.Cu" signal "VCC1")
		(22 "In10.Cu" signal "GND4")
		(24 "In11.Cu" signal "IN4")
		(26 "In12.Cu" signal "GND5")
		(28 "In13.Cu" signal "IN5")
		(30 "In14.Cu" signal "GND6")
		(32 "In15.Cu" signal "IN6")
		(34 "In16.Cu" signal "GND7")
		(2 "B.Cu" signal "BOTTOM")
		(9 "F.Adhes" user "F.Adhesive")
		(11 "B.Adhes" user "B.Adhesive")
		(13 "F.Paste" user "Package Geometry/Pastemask Top")
		(15 "B.Paste" user "Package Geometry/Pastemask Bottom")
		(5 "F.SilkS" user "Ref Des/Silkscreen Top")
		(7 "B.SilkS" user "Ref Des/Silkscreen Bottom")
		(1 "F.Mask" user "Board Geometry/Soldermask Top")
		(3 "B.Mask" user "Board Geometry/Soldermask Bottom")
		(17 "Dwgs.User" user "User.Drawings")
		(19 "Cmts.User" user "User.Comments")
		(21 "Eco1.User" user "User.Eco1")
		(23 "Eco2.User" user "User.Eco2")
		(25 "Edge.Cuts" user "Board Geometry/Outline")
		(27 "Margin" user)
		(31 "F.CrtYd" user "Package Geometry/Place Bound Top")
		(29 "B.CrtYd" user "Package Geometry/Place Bound Bottom")
		(35 "F.Fab" user "Ref Des/Assembly Top")
		(33 "B.Fab" user "Ref Des/Assembly Bottom")
	)
	(footprint ""
		(layer "F.Cu")
		(at 194.911472 -422.671748 90)
		(property "Reference" "R8102"
			(at 0 0 90)
			(layer "F.SilkS")
			(hide yes)
			(effects
				(font
					(size 1.27 1.27)
				)
			)
		)
		(property "Value" ""
			(at 0 0 90)
			(layer "F.Fab")
			(effects
				(font
					(size 1.27 1.27)
				)
			)
		)
		(duplicate_pad_numbers_are_jumpers no)
		(fp_line
			(start 0.7874 -0.4064)
			(end 0.7874 0.4064)
			(stroke
				(width 0.1524)
				(type default)
			)
			(layer "F.SilkS")
		)
		(fp_line
			(start -0.7874 -0.4064)
			(end 0.7874 -0.4064)
			(stroke
				(width 0.1524)
				(type default)
			)
			(layer "F.SilkS")
		)
		(fp_line
			(start 0.7874 0.4064)
			(end -0.7874 0.4064)
			(stroke
				(width 0.1524)
				(type default)
			)
			(layer "F.SilkS")
		)
		(fp_line
			(start -0.7874 0.4064)
			(end -0.7874 -0.4064)
			(stroke
				(width 0.1524)
				(type default)
			)
			(layer "F.SilkS")
		)
		(fp_line
			(start -0.12065 -0.305054)
			(end -0.12065 -0.2794)
			(stroke
				(width 0.1)
				(type default)
			)
			(layer "F.Fab")
		)
		(fp_line
			(start -0.67945 -0.305054)
			(end -0.12065 -0.305054)
			(stroke
				(width 0.1)
				(type default)
			)
			(layer "F.Fab")
		)
		(fp_line
			(start 0.67945 -0.3048)
			(end 0.67945 0.3048)
			(stroke
				(width 0.1)
				(type default)
			)
			(layer "F.Fab")
		)
		(fp_line
			(start 0.12065 -0.3048)
			(end 0.67945 -0.3048)
			(stroke
				(width 0.1)
				(type default)
			)
			(layer "F.Fab")
		)
		(fp_line
			(start 0.12065 -0.2794)
			(end 0.12065 -0.3048)
			(stroke
				(width 0.1)
				(type default)
			)
			(layer "F.Fab")
		)
		(fp_line
			(start -0.12065 -0.2794)
			(end 0.12065 -0.2794)
			(stroke
				(width 0.1)
				(type default)
			)
			(layer "F.Fab")
		)
		(fp_line
			(start 0.120396 0.2794)
			(end -0.12065 0.2794)
			(stroke
				(width 0.1)
				(type default)
			)
			(layer "F.Fab")
		)
		(fp_line
			(start -0.12065 0.2794)
			(end -0.12065 0.3048)
			(stroke
				(width 0.1)
				(type default)
			)
			(layer "F.Fab")
		)
		(fp_line
			(start 0.67945 0.3048)
			(end 0.120396 0.3048)
			(stroke
				(width 0.1)
				(type default)
			)
			(layer "F.Fab")
		)
		(fp_line
			(start 0.120396 0.3048)
			(end 0.120396 0.2794)
			(stroke
				(width 0.1)
				(type default)
			)
			(layer "F.Fab")
		)
		(fp_line
			(start -0.12065 0.3048)
			(end -0.67945 0.3048)
			(stroke
				(width 0.1)
				(type default)
			)
			(layer "F.Fab")
		)
		(fp_line
			(start -0.67945 0.3048)
			(end -0.67945 -0.305054)
			(stroke
				(width 0.1)
				(type default)
			)
			(layer "F.Fab")
		)
		(pad "1" smd circle
			(at -0.40005 0 90)
			(size 0 0)
			(layers "F.Cu" "F.Mask" "F.Paste")
			(net "FM_AC_PWR_BTN_R_N")
		)
		(pad "2" smd circle
			(at 0.40005 0 90)
			(size 0 0)
			(layers "F.Cu" "F.Mask" "F.Paste")
			(net "FM_AC_PWR_BTN_PDB_N")
		)
	)
	(footprint ""
		(layer "F.Cu")
		(at 142.617444 -373.03583 -90)
		(property "Reference" "C769"
			(at 0 0 270)
			(layer "F.SilkS")
			(hide yes)
			(effects
				(font
					(size 1.27 1.27)
				)
			)
		)
		(property "Value" ""
			(at 0 0 270)
			(layer "F.Fab")
			(effects
				(font
					(size 1.27 1.27)
				)
			)
		)
		(duplicate_pad_numbers_are_jumpers no)
		(fp_line
			(start -0.299974 0.150114)
			(end -0.299974 -0.150114)
			(stroke
				(width 0.1)
				(type default)
			)
			(layer "F.Fab")
		)
		(fp_line
			(start 0.299974 0.150114)
			(end -0.299974 0.150114)
			(stroke
				(width 0.1)
				(type default)
			)
			(layer "F.Fab")
		)
		(fp_line
			(start -0.299974 -0.150114)
			(end 0.299974 -0.150114)
			(stroke
				(width 0.1)
				(type default)
			)
			(layer "F.Fab")
		)
		(fp_line
			(start 0.299974 -0.150114)
			(end 0.299974 0.150114)
			(stroke
				(width 0.1)
				(type default)
			)
			(layer "F.Fab")
		)
		(pad "1" smd rect
			(at -0.2667 0 270)
			(size 0.3048 0.381)
			(layers "F.Cu" "F.Mask" "F.Paste")
			(net "P5E_CPU1_P2_TX_C_DP<2>")
		)
		(pad "2" smd rect
			(at 0.2667 0 270)
			(size 0.3048 0.381)
			(layers "F.Cu" "F.Mask" "F.Paste")
			(net "P5E_CPU1_P2_TX_DP<2>")
		)
	)
	(footprint ""
		(layer "F.Cu")
		(at 362.265976 -256.012188 90)
		(property "Reference" "C2159"
			(at 0 0 90)
			(layer "F.SilkS")
			(hide yes)
			(effects
				(font
					(size 1.27 1.27)
				)
			)
		)
		(property "Value" ""
			(at 0 0 90)
			(layer "F.Fab")
			(effects
				(font
					(size 1.27 1.27)
				)
			)
		)
		(duplicate_pad_numbers_are_jumpers no)
		(fp_line
			(start 0.7874 -0.4064)
			(end 0.7874 0.4064)
			(stroke
				(width 0.1524)
				(type default)
			)
			(layer "F.SilkS")
		)
		(fp_line
			(start -0.7874 -0.4064)
			(end 0.7874 -0.4064)
			(stroke
				(width 0.1524)
				(type default)
			)
			(layer "F.SilkS")
		)
		(fp_line
			(start 0.7874 0.4064)
			(end -0.7874 0.4064)
			(stroke
				(width 0.1524)
				(type default)
			)
			(layer "F.SilkS")
		)
		(fp_line
			(start -0.7874 0.4064)
			(end -0.7874 -0.4064)
			(stroke
				(width 0.1524)
				(type default)
			)
			(layer "F.SilkS")
		)
		(fp_line
			(start -0.12065 -0.305054)
			(end -0.12065 -0.2794)
			(stroke
				(width 0.1)
				(type default)
			)
			(layer "F.Fab")
		)
		(fp_line
			(start -0.67945 -0.305054)
			(end -0.12065 -0.305054)
			(stroke
				(width 0.1)
				(type default)
			)
			(layer "F.Fab")
		)
		(fp_line
			(start 0.67945 -0.3048)
			(end 0.67945 0.3048)
			(stroke
				(width 0.1)
				(type default)
			)
			(layer "F.Fab")
		)
		(fp_line
			(start 0.12065 -0.3048)
			(end 0.67945 -0.3048)
			(stroke
				(width 0.1)
				(type default)
			)
			(layer "F.Fab")
		)
		(fp_line
			(start 0.12065 -0.2794)
			(end 0.12065 -0.3048)
			(stroke
				(width 0.1)
				(type default)
			)
			(layer "F.Fab")
		)
		(fp_line
			(start -0.12065 -0.2794)
			(end 0.12065 -0.2794)
			(stroke
				(width 0.1)
				(type default)
			)
			(layer "F.Fab")
		)
		(fp_line
			(start 0.120396 0.2794)
			(end -0.12065 0.2794)
			(stroke
				(width 0.1)
				(type default)
			)
			(layer "F.Fab")
		)
		(fp_line
			(start -0.12065 0.2794)
			(end -0.12065 0.3048)
			(stroke
				(width 0.1)
				(type default)
			)
			(layer "F.Fab")
		)
		(fp_line
			(start 0.67945 0.3048)
			(end 0.120396 0.3048)
			(stroke
				(width 0.1)
				(type default)
			)
			(layer "F.Fab")
		)
		(fp_line
			(start 0.120396 0.3048)
			(end 0.120396 0.2794)
			(stroke
				(width 0.1)
				(type default)
			)
			(layer "F.Fab")
		)
		(fp_line
			(start -0.12065 0.3048)
			(end -0.67945 0.3048)
			(stroke
				(width 0.1)
				(type default)
			)
			(layer "F.Fab")
		)
		(fp_line
			(start -0.67945 0.3048)
			(end -0.67945 -0.305054)
			(stroke
				(width 0.1)
				(type default)
			)
			(layer "F.Fab")
		)
		(pad "1" smd circle
			(at -0.40005 0 90)
			(size 0 0)
			(layers "F.Cu" "F.Mask" "F.Paste")
			(net "PVDDCR_SOC_P0")
		)
		(pad "2" smd circle
			(at 0.40005 0 90)
			(size 0 0)
			(layers "F.Cu" "F.Mask" "F.Paste")
			(net "GND")
		)
	)
)
